# BASEBOARD_FAB2 (Tioga Pass) — schematic parts with pin connectivity, parts 2363–2363 of 4751; source: Cadence DE-HDL packaged netlist (pstxprt.dat, pstxnet.dat, pstchip.dat)

J4A1  SCONN288_H44441004  SCONN  pkg PIP  page 53
  1  \12v\(1)  = P12V_NVDIMM_DEF
  2  VSS(93)  GROUND  = GND
  3  DQ(4)  BI  = M_F_DQ<5>
  4  VSS(92)  GROUND  = GND
  5  DQ(0)  BI  = M_F_DQ<1>
  6  VSS(91)  GROUND  = GND
  7  DQS9P  BI  = M_F_DQS_DP<9>
  8  DQS9N  BI  = M_F_DQS_DN<9>
  9  VSS(90)  GROUND  = GND
  10  DQ(6)  BI  = M_F_DQ<7>
  11  VSS(89)  GROUND  = GND
  12  DQ(2)  BI  = M_F_DQ<3>
  13  VSS(88)  GROUND  = GND
  14  DQ(12)  BI  = M_F_DQ<13>
  15  VSS(87)  GROUND  = GND
  16  DQ(8)  BI  = M_F_DQ<9>
  17  VSS(86)  GROUND  = GND
  18  DQS10P  BI  = M_F_DQS_DP<10>
  19  DQS10N  BI  = M_F_DQS_DN<10>
  20  VSS(85)  GROUND  = GND
  21  DQ(14)  BI  = M_F_DQ<15>
  22  VSS(84)  GROUND  = GND
  23  DQ(10)  BI  = M_F_DQ<11>
  24  VSS(83)  GROUND  = GND
  25  DQ(20)  BI  = M_F_DQ<21>
  26  VSS(82)  GROUND  = GND
  27  DQ(16)  BI  = M_F_DQ<17>
  28  VSS(81)  GROUND  = GND
  29  DQS11P  BI  = M_F_DQS_DP<11>
  30  DQS11N  BI  = M_F_DQS_DN<11>
  31  VSS(80)  GROUND  = GND
  32  DQ(22)  BI  = M_F_DQ<23>
  33  VSS(79)  GROUND  = GND
  34  DQ(18)  BI  = M_F_DQ<19>
  35  VSS(78)  GROUND  = GND
  36  DQ(28)  BI  = M_F_DQ<29>
  37  VSS(77)  GROUND  = GND
  38  DQ(24)  BI  = M_F_DQ<25>
  39  VSS(76)  GROUND  = GND
  40  DQS12P  BI  = M_F_DQS_DP<12>
  41  DQS12N  BI  = M_F_DQS_DN<12>
  42  VSS(75)  GROUND  = GND
  43  DQ(30)  BI  = M_F_DQ<31>
  44  VSS(74)  GROUND  = GND
  45  DQ(26)  BI  = M_F_DQ<27>
  46  VSS(73)  GROUND  = GND
  47  CB(4)  BI  = M_F_ECC<5>
  48  VSS(72)  GROUND  = GND
  49  CB(0)  BI  = M_F_ECC<1>
  50  VSS(71)  GROUND  = GND
  51  DQS17P  BI  = M_F_DQS_DP<17>
  52  DQS17N  BI  = M_F_DQS_DN<17>
  53  VSS(70)  GROUND  = GND
  54  CB(6)  BI  = M_F_ECC<7>
  55  VSS(69)  GROUND  = GND
  56  CB(2)  BI  = M_F_ECC<3>
  57  VSS(68)  GROUND  = GND
  58  RESET_N  BI  = M_DEF_RST_N
  59  VDD(25)  POWER  = PVDDQ_DEF
  60  CKE(0)  BI  = M_F_CKE<0>
  61  VDD(24)  POWER  = PVDDQ_DEF
  62  ACT_N  BI  = M_F_ACT_N
  63  BG(0)  BI  = M_F_BG<0>
  64  VDD(23)  POWER  = PVDDQ_DEF
  65  A12  BI  = M_F_MA<12>
  66  A9  BI  = M_F_MA<9>
  67  VDD(22)  POWER  = PVDDQ_DEF
  68  A8  BI  = M_F_MA<8>
  69  A6  BI  = M_F_MA<6>
  70  VDD(21)  POWER  = PVDDQ_DEF
  71  A3  BI  = M_F_MA<3>
  72  A1  BI  = M_F_MA<1>
  73  VDD(20)  POWER  = PVDDQ_DEF
  74  CK0P  BI  = M_F_CLK_DP<0>
  75  CK0N  BI  = M_F_CLK_DN<0>
  76  VDD(19)  POWER  = PVDDQ_DEF
  77  VTT(1)  POWER  = PVTT_DEF
  78  EVENT_N  BI  = FM_DIMM_EVENT_COD_N
  79  A0  BI  = M_F_MA<0>
  80  VDD(18)  POWER  = PVDDQ_DEF
  81  BA(0)  BI  = M_F_BA<0>
  82  A16_RAS_N  BI  = M_F_MA<16>
  83  VDD(17)  POWER  = PVDDQ_DEF
  84  S0_N  BI  = M_F_CS_N<0>
  85  VDD(16)  POWER  = PVDDQ_DEF
  86  A15_CAS_N  BI  = M_F_MA<15>
  87  ODT(0)  BI  = M_F_ODT<0>
  88  VDD(15)  POWER  = PVDDQ_DEF
  89  S1_N  BI  = M_F_CS_N<1>
  90  VDD(14)  POWER  = PVDDQ_DEF
  91  ODT(1)  BI  = M_F_ODT<1>
  92  VDD(13)  POWER  = PVDDQ_DEF
  93  S2_N_C(0)  BI  = M_F_CS_N<2>
  94  VSS(67)  GROUND  = GND
  95  DQ(36)  BI  = M_F_DQ<37>
  96  VSS(66)  GROUND  = GND
  97  DQ(32)  BI  = M_F_DQ<33>
  98  VSS(65)  GROUND  = GND
  99  DQS13P  BI  = M_F_DQS_DP<13>
  100  DQS13N  BI  = M_F_DQS_DN<13>
  101  VSS(64)  GROUND  = GND
  102  DQ(38)  BI  = M_F_DQ<39>
  103  VSS(63)  GROUND  = GND
  104  DQ(34)  BI  = M_F_DQ<35>
  105  VSS(62)  GROUND  = GND
  106  DQ(44)  BI  = M_F_DQ<45>
  107  VSS(61)  GROUND  = GND
  108  DQ(40)  BI  = M_F_DQ<41>
  109  VSS(60)  GROUND  = GND
  110  DQS14P  BI  = M_F_DQS_DP<14>
  111  DQS14N  BI  = M_F_DQS_DN<14>
  112  VSS(59)  GROUND  = GND
  113  DQ(46)  BI  = M_F_DQ<47>
  114  VSS(58)  GROUND  = GND
  115  DQ(42)  BI  = M_F_DQ<43>
  116  VSS(57)  GROUND  = GND
  117  DQ(52)  BI  = M_F_DQ<53>
  118  VSS(56)  GROUND  = GND
  119  DQ(48)  BI  = M_F_DQ<49>
  120  VSS(55)  GROUND  = GND
  121  DQS15P  BI  = M_F_DQS_DP<15>
  122  DQS15N  BI  = M_F_DQS_DN<15>
  123  VSS(54)  GROUND  = GND
  124  DQ(54)  BI  = M_F_DQ<55>
  125  VSS(53)  GROUND  = GND
  126  DQ(50)  BI  = M_F_DQ<51>
  127  VSS(52)  GROUND  = GND
  128  DQ(60)  BI  = M_F_DQ<61>
  129  VSS(51)  GROUND  = GND
  130  DQ(56)  BI  = M_F_DQ<57>
  131  VSS(50)  GROUND  = GND
  132  DQS16P  BI  = M_F_DQS_DP<16>
  133  DQS16N  BI  = M_F_DQS_DN<16>
  134  VSS(49)  GROUND  = GND
  135  DQ(62)  BI  = M_F_DQ<63>
  136  VSS(48)  GROUND  = GND
  137  DQ(58)  BI  = M_F_DQ<59>
  138  VSS(47)  GROUND  = GND
  139  SA(0)  BI  = GND
  140  SA(1)  BI  = GND
  141  SCL  BI  = SMB_DDR_DEF_VPP_SCL
  142  VPP(4)  POWER  = PVPP_DEF
  143  VPP(3)  POWER  = PVPP_DEF
  144  RFU(2)  BI  = TP_CH_F_DIMM_F0_RFU_2
  145  \12v\(0)  = P12V_NVDIMM_DEF
  146  VREFCA  BI  = M_F_VREF
  147  VSS(46)  GROUND  = GND
  148  DQ(5)  BI  = M_F_DQ<4>
  149  VSS(45)  GROUND  = GND
  150  DQ(1)  BI  = M_F_DQ<0>
  151  VSS(44)  GROUND  = GND
  152  DQS0N  BI  = M_F_DQS_DN<0>
  153  DQS0P  BI  = M_F_DQS_DP<0>
  154  VSS(43)  GROUND  = GND
  155  DQ(7)  BI  = M_F_DQ<6>
  156  VSS(42)  GROUND  = GND
  157  DQ(3)  BI  = M_F_DQ<2>
  158  VSS(41)  GROUND  = GND
  159  DQ(13)  BI  = M_F_DQ<12>
  160  VSS(40)  GROUND  = GND
  161  DQ(9)  BI  = M_F_DQ<8>
  162  VSS(39)  GROUND  = GND
  163  DQS1N  BI  = M_F_DQS_DN<1>
  164  DQS1P  BI  = M_F_DQS_DP<1>
  165  VSS(38)  GROUND  = GND
  166  DQ(15)  BI  = M_F_DQ<14>
  167  VSS(37)  GROUND  = GND
  168  DQ(11)  BI  = M_F_DQ<10>
  169  VSS(36)  GROUND  = GND
  170  DQ(21)  BI  = M_F_DQ<20>
  171  VSS(35)  GROUND  = GND
  172  DQ(17)  BI  = M_F_DQ<16>
  173  VSS(34)  GROUND  = GND
  174  DQS2N  BI  = M_F_DQS_DN<2>
  175  DQS2P  BI  = M_F_DQS_DP<2>
  176  VSS(33)  GROUND  = GND
  177  DQ(23)  BI  = M_F_DQ<22>
  178  VSS(32)  GROUND  = GND
  179  DQ(19)  BI  = M_F_DQ<18>
  180  VSS(31)  GROUND  = GND
  181  DQ(29)  BI  = M_F_DQ<28>
  182  VSS(30)  GROUND  = GND
  183  DQ(25)  BI  = M_F_DQ<24>
  184  VSS(29)  GROUND  = GND
  185  DQS3N  BI  = M_F_DQS_DN<3>
  186  DQS3P  BI  = M_F_DQS_DP<3>
  187  VSS(28)  GROUND  = GND
  188  DQ(31)  BI  = M_F_DQ<30>
  189  VSS(27)  GROUND  = GND
  190  DQ(27)  BI  = M_F_DQ<26>
  191  VSS(26)  GROUND  = GND
  192  CB(5)  BI  = M_F_ECC<4>
  193  VSS(25)  GROUND  = GND
  194  CB(1)  BI  = M_F_ECC<0>
  195  VSS(24)  GROUND  = GND
  196  DQS8N  BI  = M_F_DQS_DN<8>
  197  DQS8P  BI  = M_F_DQS_DP<8>
  198  VSS(23)  GROUND  = GND
  199  CB(7)  BI  = M_F_ECC<6>
  200  VSS(22)  GROUND  = GND
  201  CB(3)  BI  = M_F_ECC<2>
  202  VSS(21)  GROUND  = GND
  203  CKE(1)  BI  = M_F_CKE<1>
  204  VDD(12)  POWER  = PVDDQ_DEF
  205  RFU(0)  BI  = TP_CH_F_DIMM_F0_RFU_0
  206  VDD(11)  POWER  = PVDDQ_DEF
  207  BG(1)  BI  = M_F_BG<1>
  208  ALERT_N  BI  = M_F_ALERT_N
  209  VDD(10)  POWER  = PVDDQ_DEF
  210  A11  BI  = M_F_MA<11>
  211  A7  BI  = M_F_MA<7>
  212  VDD(9)  POWER  = PVDDQ_DEF
  213  A5  BI  = M_F_MA<5>
  214  A4  BI  = M_F_MA<4>
  215  VDD(8)  POWER  = PVDDQ_DEF
  216  A2  BI  = M_F_MA<2>
  217  VDD(7)  POWER  = PVDDQ_DEF
  218  CK1P  BI  = M_F_CLK_DP<1>
  219  CK1N  BI  = M_F_CLK_DN<1>
  220  VDD(6)  POWER  = PVDDQ_DEF
  221  VTT(0)  POWER  = PVTT_DEF
  222  PAR  BI  = M_F_PAR
  223  VDD(5)  POWER  = PVDDQ_DEF
  224  BA(1)  BI  = M_F_BA<1>
  225  A10  BI  = M_F_MA<10>
  226  VDD(4)  POWER  = PVDDQ_DEF
  227  RFU(1)  BI  = TP_CH_F_DIMM_F0_RFU_1
  228  A14_WE_N  BI  = M_F_MA<14>
  229  VDD(3)  POWER  = PVDDQ_DEF
  230  SAVE_N_NC  BI  = FM_ADR_COMPLETE_DEF_N
  231  VDD(2)  POWER  = PVDDQ_DEF
  232  A13  BI  = M_F_MA<13>
  233  VDD(1)  POWER  = PVDDQ_DEF
  234  A17  BI  = M_F_MA<17>
  235  C(2)  BI  = M_F_C<2>
  236  VDD(0)  POWER  = PVDDQ_DEF
  237  S3_N_C(1)  BI  = M_F_CS_N<3>
  238  SA(2)  BI  = PVPP_DEF
  239  VSS(20)  GROUND  = GND
  240  DQ(37)  BI  = M_F_DQ<36>
  241  VSS(19)  GROUND  = GND
  242  DQ(33)  BI  = M_F_DQ<32>
  243  VSS(18)  GROUND  = GND
  244  DQS4N  BI  = M_F_DQS_DN<4>
  245  DQS4P  BI  = M_F_DQS_DP<4>
  246  VSS(17)  GROUND  = GND
  247  DQ(39)  BI  = M_F_DQ<38>
  248  VSS(16)  GROUND  = GND
  249  DQ(35)  BI  = M_F_DQ<34>
  250  VSS(15)  GROUND  = GND
  251  DQ(45)  BI  = M_F_DQ<44>
  252  VSS(14)  GROUND  = GND
  253  DQ(41)  BI  = M_F_DQ<40>
  254  VSS(13)  GROUND  = GND
  255  DQS5N  BI  = M_F_DQS_DN<5>
  256  DQS5P  BI  = M_F_DQS_DP<5>
  257  VSS(12)  GROUND  = GND
  258  DQ(47)  BI  = M_F_DQ<46>
  259  VSS(11)  GROUND  = GND
  260  DQ(43)  BI  = M_F_DQ<42>
  261  VSS(10)  GROUND  = GND
  262  DQ(53)  BI  = M_F_DQ<52>
  263  VSS(9)  GROUND  = GND
  264  DQ(49)  BI  = M_F_DQ<48>
  265  VSS(8)  GROUND  = GND
  266  DQS6N  BI  = M_F_DQS_DN<6>
  267  DQS6P  BI  = M_F_DQS_DP<6>
  268  VSS(7)  GROUND  = GND
  269  DQ(55)  BI  = M_F_DQ<54>
  270  VSS(6)  GROUND  = GND
  271  DQ(51)  BI  = M_F_DQ<50>
  272  VSS(5)  GROUND  = GND
  273  DQ(61)  BI  = M_F_DQ<60>
  274  VSS(4)  GROUND  = GND
  275  DQ(57)  BI  = M_F_DQ<56>
  276  VSS(3)  GROUND  = GND
  277  DQS7N  BI  = M_F_DQS_DN<7>
  278  DQS7P  BI  = M_F_DQS_DP<7>
  279  VSS(2)  GROUND  = GND
  280  DQ(63)  BI  = M_F_DQ<62>
  281  VSS(1)  GROUND  = GND
  282  DQ(59)  BI  = M_F_DQ<58>
  283  VSS(0)  GROUND  = GND
  284  VDDSPD  BI  = PVPP_DEF
  285  SDA  BI  = SMB_DDR_DEF_VPP_SDA
  286  VPP(1)  POWER  = PVPP_DEF
  287  VPP(0)  POWER  = PVPP_DEF
  288  VPP(2)  POWER  = PVPP_DEF
